(kicad_pcb
	(version 20260206)
	(generator "pcbnew")
	(generator_version "10.0")
	(general
		(thickness 1.6)
		(legacy_teardrops no)
	)
	(paper "A4")
	(title_block
		(title "fcb — Lightning_FCB_BRD.brd")
		(comment 1 "Lightning (Wiwynn / Facebook NVMe JBOF) / footprints 251-256 of 495")
	)
	(layers
		(0 "F.Cu" signal "TOP")
		(4 "In1.Cu" signal "L2GND")
		(6 "In2.Cu" signal "L3VCC")
		(2 "B.Cu" signal "BOTTOM")
		(9 "F.Adhes" user "F.Adhesive")
		(11 "B.Adhes" user "B.Adhesive")
		(13 "F.Paste" user "Package Geometry/Pastemask Top")
		(15 "B.Paste" user "Package Geometry/Pastemask Bottom")
		(5 "F.SilkS" user "Ref Des/Silkscreen Top")
		(7 "B.SilkS" user "Ref Des/Silkscreen Bottom")
		(1 "F.Mask" user "Board Geometry/Soldermask Top")
		(3 "B.Mask" user "Board Geometry/Soldermask Bottom")
		(17 "Dwgs.User" user "User.Drawings")
		(19 "Cmts.User" user "User.Comments")
		(21 "Eco1.User" user "User.Eco1")
		(23 "Eco2.User" user "User.Eco2")
		(25 "Edge.Cuts" user "Board Geometry/Outline")
		(27 "Margin" user)
		(31 "F.CrtYd" user "Package Geometry/Place Bound Top")
		(29 "B.CrtYd" user "Package Geometry/Place Bound Bottom")
		(35 "F.Fab" user "Ref Des/Assembly Top")
		(33 "B.Fab" user "Ref Des/Assembly Bottom")
	)
	(footprint ""
		(layer "F.Cu")
		(at 12.2428 -55.2196 -90)
		(property "Reference" "R63"
			(at 0 0 270)
			(layer "F.SilkS")
			(hide yes)
			(effects
				(font
					(size 1.27 1.27)
				)
			)
		)
		(property "Value" "0R2J-2-GP"
			(at 0.064008 -3.993896 270)
			(unlocked yes)
			(layer "F.Fab")
			(hide yes)
			(effects
				(font
					(size 1.016 1.016)
					(thickness 0.1524)
				)
			)
		)
		(property "Device Type" "R402H16"
			(at 0.064008 -5.517896 270)
			(unlocked yes)
			(layer "F.Fab")
			(hide yes)
			(effects
				(font
					(size 1.016 1.016)
					(thickness 0.1524)
				)
			)
		)
		(duplicate_pad_numbers_are_jumpers no)
		(fp_line
			(start -0.508 -0.9398)
			(end -0.508 0.9398)
			(stroke
				(width 0.1524)
				(type default)
			)
			(layer "F.SilkS")
		)
		(fp_line
			(start 0.508 -0.9398)
			(end -0.508 -0.9398)
			(stroke
				(width 0.1524)
				(type default)
			)
			(layer "F.SilkS")
		)
		(fp_rect
			(start -0.508 0.9398)
			(end 0.508 -0.9398)
			(stroke
				(width 0)
				(type default)
			)
			(fill no)
			(layer "F.CrtYd")
		)
		(fp_rect
			(start -0.508 0.9398)
			(end 0.508 -0.9398)
			(stroke
				(width 0)
				(type default)
			)
			(fill no)
			(layer "F.Fab")
		)
		(pad "1" smd custom
			(at 0 -0.4445 270)
			(size 0.1397 0.1397)
			(layers "F.Cu" "F.Mask" "F.Paste")
			(net "SELF_TRAY_PRESENT_LOWER")
			(options
				(clearance outline)
				(anchor circle)
			)
			(primitives
				(gr_poly
					(pts
						(arc
							(start -0.1778 -0.2794)
							(mid -0.249642 -0.249642)
							(end -0.2794 -0.1778)
						)
						(arc
							(start -0.2794 0.1778)
							(mid -0.249642 0.249642)
							(end -0.1778 0.2794)
						)
						(arc
							(start 0.1778 0.2794)
							(mid 0.249642 0.249642)
							(end 0.2794 0.1778)
						)
						(arc
							(start 0.2794 -0.1778)
							(mid 0.249642 -0.249642)
							(end 0.1778 -0.2794)
						)
					)
					(width 0)
					(fill yes)
				)
			)
		)
		(pad "2" smd custom
			(at 0 0.4445 270)
			(size 0.1397 0.1397)
			(layers "F.Cu" "F.Mask" "F.Paste")
			(net "PEER_TRAY PRESENT_UPPER")
			(options
				(clearance outline)
				(anchor circle)
			)
			(primitives
				(gr_poly
					(pts
						(arc
							(start -0.1778 -0.2794)
							(mid -0.249642 -0.249642)
							(end -0.2794 -0.1778)
						)
						(arc
							(start -0.2794 0.1778)
							(mid -0.249642 0.249642)
							(end -0.1778 0.2794)
						)
						(arc
							(start 0.1778 0.2794)
							(mid 0.249642 0.249642)
							(end 0.2794 0.1778)
						)
						(arc
							(start 0.2794 -0.1778)
							(mid 0.249642 -0.249642)
							(end 0.1778 -0.2794)
						)
					)
					(width 0)
					(fill yes)
				)
			)
		)
	)
	(footprint ""
		(layer "F.Cu")
		(at 27.500072 -144.999964 90)
		(property "Reference" "Q1"
			(at 0 0 90)
			(layer "F.SilkS")
			(hide yes)
			(effects
				(font
					(size 1.27 1.27)
				)
			)
		)
		(property "Value" "PMBS3904-1-GP"
			(at 0 -9.0932 90)
			(unlocked yes)
			(layer "F.Fab")
			(hide yes)
			(effects
				(font
					(size 1.016 1.016)
					(thickness 0.1524)
				)
			)
		)
		(property "Device Type" "SOT-23-10H44"
			(at 0 -10.6172 90)
			(unlocked yes)
			(layer "F.Fab")
			(hide yes)
			(effects
				(font
					(size 1.016 1.016)
					(thickness 0.1524)
				)
			)
		)
		(duplicate_pad_numbers_are_jumpers no)
		(fp_line
			(start 1.651 -1.778)
			(end -1.651 -1.778)
			(stroke
				(width 0.1524)
				(type default)
			)
			(layer "F.SilkS")
		)
		(fp_line
			(start -1.651 -1.778)
			(end -1.651 1.778)
			(stroke
				(width 0.1524)
				(type default)
			)
			(layer "F.SilkS")
		)
		(fp_line
			(start 1.651 1.778)
			(end 1.651 -1.778)
			(stroke
				(width 0.1524)
				(type default)
			)
			(layer "F.SilkS")
		)
		(fp_line
			(start -1.651 1.778)
			(end 1.651 1.778)
			(stroke
				(width 0.1524)
				(type default)
			)
			(layer "F.SilkS")
		)
		(fp_line
			(start -0.9906 1.86309)
			(end -0.701294 2.15265)
			(stroke
				(width 0.0127)
				(type default)
			)
			(layer "F.SilkS")
		)
		(fp_line
			(start -0.994156 1.8669)
			(end -0.987044 1.8669)
			(stroke
				(width 0.0127)
				(type default)
			)
			(layer "F.SilkS")
		)
		(fp_line
			(start -1.003808 1.876552)
			(end -0.977646 1.876552)
			(stroke
				(width 0.0127)
				(type default)
			)
			(layer "F.SilkS")
		)
		(fp_line
			(start -0.635 1.8796)
			(end -1.7526 1.8796)
			(stroke
				(width 0.3302)
				(type default)
			)
			(layer "F.SilkS")
		)
		(fp_line
			(start -1.7526 1.8796)
			(end -1.7526 0.9906)
			(stroke
				(width 0.3302)
				(type default)
			)
			(layer "F.SilkS")
		)
		(fp_line
			(start -1.013206 1.88595)
			(end -0.967994 1.88595)
			(stroke
				(width 0.0127)
				(type default)
			)
			(layer "F.SilkS")
		)
		(fp_line
			(start -1.022858 1.895602)
			(end -0.958596 1.895602)
			(stroke
				(width 0.0127)
				(type default)
			)
			(layer "F.SilkS")
		)
		(fp_line
			(start -1.032256 1.905)
			(end -0.948944 1.905)
			(stroke
				(width 0.0127)
				(type default)
			)
			(layer "F.SilkS")
		)
		(fp_line
			(start -1.041908 1.914652)
			(end -0.939546 1.914652)
			(stroke
				(width 0.0127)
				(type default)
			)
			(layer "F.SilkS")
		)
		(fp_line
			(start -1.051306 1.92405)
			(end -0.929894 1.92405)
			(stroke
				(width 0.0127)
				(type default)
			)
			(layer "F.SilkS")
		)
		(fp_line
			(start -1.060958 1.933702)
			(end -0.920496 1.933702)
			(stroke
				(width 0.0127)
				(type default)
			)
			(layer "F.SilkS")
		)
		(fp_line
			(start -1.070356 1.9431)
			(end -0.910844 1.9431)
			(stroke
				(width 0.0127)
				(type default)
			)
			(layer "F.SilkS")
		)
		(fp_line
			(start -1.080008 1.952752)
			(end -0.901446 1.952752)
			(stroke
				(width 0.0127)
				(type default)
			)
			(layer "F.SilkS")
		)
		(fp_line
			(start -1.089406 1.96215)
			(end -0.891794 1.96215)
			(stroke
				(width 0.0127)
				(type default)
			)
			(layer "F.SilkS")
		)
		(fp_line
			(start -1.099058 1.971802)
			(end -0.882396 1.971802)
			(stroke
				(width 0.0127)
				(type default)
			)
			(layer "F.SilkS")
		)
		(fp_line
			(start -1.108456 1.9812)
			(end -0.872744 1.9812)
			(stroke
				(width 0.0127)
				(type default)
			)
			(layer "F.SilkS")
		)
		(fp_line
			(start -1.118108 1.990852)
			(end -0.863346 1.990852)
			(stroke
				(width 0.0127)
				(type default)
			)
			(layer "F.SilkS")
		)
		(fp_line
			(start -1.127506 2.00025)
			(end -0.853694 2.00025)
			(stroke
				(width 0.0127)
				(type default)
			)
			(layer "F.SilkS")
		)
		(fp_line
			(start -1.137158 2.009902)
			(end -0.844296 2.009902)
			(stroke
				(width 0.0127)
				(type default)
			)
			(layer "F.SilkS")
		)
		(fp_line
			(start -1.146556 2.0193)
			(end -0.834644 2.0193)
			(stroke
				(width 0.0127)
				(type default)
			)
			(layer "F.SilkS")
		)
		(fp_line
			(start -1.156208 2.028952)
			(end -0.825246 2.028952)
			(stroke
				(width 0.0127)
				(type default)
			)
			(layer "F.SilkS")
		)
		(fp_line
			(start -1.165606 2.03835)
			(end -0.815594 2.03835)
			(stroke
				(width 0.0127)
				(type default)
			)
			(layer "F.SilkS")
		)
		(fp_line
			(start -1.175258 2.048002)
			(end -0.806196 2.048002)
			(stroke
				(width 0.0127)
				(type default)
			)
			(layer "F.SilkS")
		)
		(fp_line
			(start -1.184656 2.0574)
			(end -0.796544 2.0574)
			(stroke
				(width 0.0127)
				(type default)
			)
			(layer "F.SilkS")
		)
		(fp_line
			(start -1.194308 2.067052)
			(end -0.787146 2.067052)
			(stroke
				(width 0.0127)
				(type default)
			)
			(layer "F.SilkS")
		)
		(fp_line
			(start -1.203706 2.07645)
			(end -0.777494 2.07645)
			(stroke
				(width 0.0127)
				(type default)
			)
			(layer "F.SilkS")
		)
		(fp_line
			(start -1.213358 2.086102)
			(end -0.768096 2.086102)
			(stroke
				(width 0.0127)
				(type default)
			)
			(layer "F.SilkS")
		)
		(fp_line
			(start -1.222756 2.0955)
			(end -0.758444 2.0955)
			(stroke
				(width 0.0127)
				(type default)
			)
			(layer "F.SilkS")
		)
		(fp_line
			(start -1.232408 2.105152)
			(end -0.749046 2.105152)
			(stroke
				(width 0.0127)
				(type default)
			)
			(layer "F.SilkS")
		)
		(fp_line
			(start -1.241806 2.11455)
			(end -0.739394 2.11455)
			(stroke
				(width 0.0127)
				(type default)
			)
			(layer "F.SilkS")
		)
		(fp_line
			(start -1.251458 2.124202)
			(end -0.729996 2.124202)
			(stroke
				(width 0.0127)
				(type default)
			)
			(layer "F.SilkS")
		)
		(fp_line
			(start -1.260856 2.1336)
			(end -0.720344 2.1336)
			(stroke
				(width 0.0127)
				(type default)
			)
			(layer "F.SilkS")
		)
		(fp_line
			(start -0.719074 2.145538)
			(end -1.265936 2.14122)
			(stroke
				(width 0.0127)
				(type default)
			)
			(layer "F.SilkS")
		)
		(fp_line
			(start -1.279398 2.152142)
			(end -0.9906 1.86309)
			(stroke
				(width 0.0127)
				(type default)
			)
			(layer "F.SilkS")
		)
		(fp_line
			(start -0.71628 2.15265)
			(end -1.26492 2.15265)
			(stroke
				(width 0.0127)
				(type default)
			)
			(layer "F.SilkS")
		)
		(fp_line
			(start -1.279144 2.15265)
			(end -0.701294 2.15265)
			(stroke
				(width 0.0127)
				(type default)
			)
			(layer "F.SilkS")
		)
		(fp_poly
			(pts
				(xy -1.285748 2.159) (xy -1.285748 1.8796) (xy -1.778 1.8796) (xy -1.778 -1.8796) (xy 1.778 -1.8796)
				(xy 1.778 1.8796) (xy -0.694944 1.8796) (xy -0.694944 2.159)
			)
			(stroke
				(width 0)
				(type default)
			)
			(fill no)
			(layer "F.CrtYd")
		)
		(fp_poly
			(pts
				(xy -1.285748 2.159) (xy -1.285748 1.8796) (xy -1.778 1.8796) (xy -1.778 -1.8796) (xy 1.778 -1.8796)
				(xy 1.778 1.8796) (xy -0.694944 1.8796) (xy -0.694944 2.159)
			)
			(stroke
				(width 0)
				(type default)
			)
			(fill no)
			(layer "F.Fab")
		)
		(pad "1" smd rect
			(at -0.98425 0.9525 90)
			(size 0.762 1.143)
			(layers "F.Cu" "F.Mask" "F.Paste")
			(net "NCT7904_D1+")
		)
		(pad "2" smd rect
			(at 0.98425 0.9525 90)
			(size 0.762 1.143)
			(layers "F.Cu" "F.Mask" "F.Paste")
			(net "NCT7904_D1-")
		)
		(pad "3" smd rect
			(at 0 -0.9525 90)
			(size 0.762 1.143)
			(layers "F.Cu" "F.Mask" "F.Paste")
			(net "NCT7904_D1+")
		)
	)
	(footprint ""
		(layer "F.Cu")
		(at 32.004 -180.467 90)
		(property "Reference" "D13"
			(at 0 0 90)
			(layer "F.SilkS")
			(hide yes)
			(effects
				(font
					(size 1.27 1.27)
				)
			)
		)
		(property "Value" "BZG05C3V9-GP"
			(at 0.027178 -8.482076 90)
			(unlocked yes)
			(layer "F.Fab")
			(hide yes)
			(effects
				(font
					(size 1.016 1.016)
					(thickness 0.1524)
				)
			)
		)
		(property "Device Type" "D5226155AKH91"
			(at 0.027178 -10.006076 90)
			(unlocked yes)
			(layer "F.Fab")
			(hide yes)
			(effects
				(font
					(size 1.016 1.016)
					(thickness 0.1524)
				)
			)
		)
		(duplicate_pad_numbers_are_jumpers no)
		(fp_line
			(start 1.524 -3.4798)
			(end -1.524 -3.4798)
			(stroke
				(width 0.1524)
				(type default)
			)
			(layer "F.SilkS")
		)
		(fp_line
			(start -1.524 -3.4798)
			(end -1.524 3.4798)
			(stroke
				(width 0.1524)
				(type default)
			)
			(layer "F.SilkS")
		)
		(fp_line
			(start 1.524 3.4798)
			(end 1.524 -3.4798)
			(stroke
				(width 0.1524)
				(type default)
			)
			(layer "F.SilkS")
		)
		(fp_line
			(start -1.524 3.4798)
			(end 1.524 3.4798)
			(stroke
				(width 0.1524)
				(type default)
			)
			(layer "F.SilkS")
		)
		(fp_line
			(start -1.524 3.6576)
			(end 1.524 3.6576)
			(stroke
				(width 0.508)
				(type default)
			)
			(layer "F.SilkS")
		)
		(fp_rect
			(start -1.27 2.6035)
			(end 1.27 -2.6035)
			(stroke
				(width 0)
				(type default)
			)
			(fill no)
			(layer "F.CrtYd")
		)
		(fp_poly
			(pts
				(xy 1.778 -0.2921) (xy 1.27 -0.2921) (xy 1.27 -2.6035) (xy -1.27 -2.6035) (xy -1.27 2.6035) (xy 1.27 2.6035)
				(xy 1.27 -0.2794) (xy 1.778 -0.2794) (xy 1.778 3.556) (xy -1.778 3.556) (xy -1.778 -3.556) (xy 1.778 -3.556)
			)
			(stroke
				(width 0)
				(type default)
			)
			(fill no)
			(layer "F.CrtYd")
		)
		(fp_rect
			(start -1.778 3.556)
			(end 1.778 -3.556)
			(stroke
				(width 0)
				(type default)
			)
			(fill no)
			(layer "F.Fab")
		)
		(pad "A" smd rect
			(at 0 -2.212086 90)
			(size 1.8034 2.032)
			(layers "F.Cu" "F.Mask" "F.Paste")
			(net "GND")
		)
		(pad "K" smd rect
			(at 0 2.212086 90)
			(size 1.8034 2.032)
			(layers "F.Cu" "F.Mask" "F.Paste")
			(net "P3V3_AUX_BJT_B")
		)
	)
	(footprint ""
		(layer "F.Cu")
		(at 22.352 -188.0616 90)
		(property "Reference" "D6"
			(at 0 0 90)
			(layer "F.SilkS")
			(hide yes)
			(effects
				(font
					(size 1.27 1.27)
				)
			)
		)
		(property "Value" "BAS16H-GP"
			(at 0 -5.5372 90)
			(unlocked yes)
			(layer "F.Fab")
			(hide yes)
			(effects
				(font
					(size 1.016 1.016)
					(thickness 0.1524)
				)
			)
		)
		(property "Device Type" "SOD123AKH48"
			(at 0 -7.0612 90)
			(unlocked yes)
			(layer "F.Fab")
			(hide yes)
			(effects
				(font
					(size 1.016 1.016)
					(thickness 0.1524)
				)
			)
		)
		(duplicate_pad_numbers_are_jumpers no)
		(fp_line
			(start 1.016 -2.667)
			(end -1.016 -2.667)
			(stroke
				(width 0.1524)
				(type default)
			)
			(layer "F.SilkS")
		)
		(fp_line
			(start -1.016 -2.667)
			(end -1.016 2.667)
			(stroke
				(width 0.1524)
				(type default)
			)
			(layer "F.SilkS")
		)
		(fp_line
			(start 1.016 2.667)
			(end 1.016 -2.667)
			(stroke
				(width 0.1524)
				(type default)
			)
			(layer "F.SilkS")
		)
		(fp_line
			(start -1.016 2.667)
			(end 1.016 2.667)
			(stroke
				(width 0.1524)
				(type default)
			)
			(layer "F.SilkS")
		)
		(fp_line
			(start 0.889 2.921)
			(end -0.889 2.921)
			(stroke
				(width 0.508)
				(type default)
			)
			(layer "F.SilkS")
		)
		(fp_rect
			(start -1.143 3.175)
			(end 1.143 -2.794)
			(stroke
				(width 0)
				(type default)
			)
			(fill no)
			(layer "F.CrtYd")
		)
		(fp_poly
			(pts
				(xy -1.143 -2.794) (xy 1.143 -2.794) (xy 1.143 3.175) (xy -1.143 3.175)
			)
			(stroke
				(width 0)
				(type default)
			)
			(fill no)
			(layer "F.Fab")
		)
		(pad "A" smd rect
			(at 0 -1.6891 90)
			(size 0.889 1.397)
			(layers "F.Cu" "F.Mask" "F.Paste")
			(net "FAN_TACH8")
		)
		(pad "K" smd rect
			(at 0 1.6891 90)
			(size 0.889 1.397)
			(layers "F.Cu" "F.Mask" "F.Paste")
			(net "P12V")
		)
	)
	(footprint ""
		(layer "F.Cu")
		(at 39.784274 -363.062774 180)
		(property "Reference" "PR42"
			(at 0 0 180)
			(layer "F.SilkS")
			(hide yes)
			(effects
				(font
					(size 1.27 1.27)
				)
			)
		)
		(property "Value" "10KR2F-2-GP"
			(at 0.064008 -3.993896 180)
			(unlocked yes)
			(layer "F.Fab")
			(hide yes)
			(effects
				(font
					(size 1.016 1.016)
					(thickness 0.1524)
				)
			)
		)
		(property "Device Type" "R402H16"
			(at 0.064008 -5.517896 180)
			(unlocked yes)
			(layer "F.Fab")
			(hide yes)
			(effects
				(font
					(size 1.016 1.016)
					(thickness 0.1524)
				)
			)
		)
		(duplicate_pad_numbers_are_jumpers no)
		(fp_line
			(start 0.508 -0.9398)
			(end -0.508 -0.9398)
			(stroke
				(width 0.1524)
				(type default)
			)
			(layer "F.SilkS")
		)
		(fp_line
			(start -0.508 -0.9398)
			(end -0.508 0.9398)
			(stroke
				(width 0.1524)
				(type default)
			)
			(layer "F.SilkS")
		)
		(fp_rect
			(start -0.508 0.9398)
			(end 0.508 -0.9398)
			(stroke
				(width 0)
				(type default)
			)
			(fill no)
			(layer "F.CrtYd")
		)
		(fp_rect
			(start -0.508 0.9398)
			(end 0.508 -0.9398)
			(stroke
				(width 0)
				(type default)
			)
			(fill no)
			(layer "F.Fab")
		)
		(pad "1" smd custom
			(at 0 -0.4445 180)
			(size 0.1397 0.1397)
			(layers "F.Cu" "F.Mask" "F.Paste")
			(net "TEMP_ALM#_JP_1")
			(options
				(clearance outline)
				(anchor circle)
			)
			(primitives
				(gr_poly
					(pts
						(arc
							(start -0.1778 -0.2794)
							(mid -0.249642 -0.249642)
							(end -0.2794 -0.1778)
						)
						(arc
							(start -0.2794 0.1778)
							(mid -0.249642 0.249642)
							(end -0.1778 0.2794)
						)
						(arc
							(start 0.1778 0.2794)
							(mid 0.249642 0.249642)
							(end 0.2794 0.1778)
						)
						(arc
							(start 0.2794 -0.1778)
							(mid 0.249642 -0.249642)
							(end 0.1778 -0.2794)
						)
					)
					(width 0)
					(fill yes)
				)
			)
		)
		(pad "2" smd custom
			(at 0 0.4445 180)
			(size 0.1397 0.1397)
			(layers "F.Cu" "F.Mask" "F.Paste")
			(net "TEMP_ALM#_REVERSE")
			(options
				(clearance outline)
				(anchor circle)
			)
			(primitives
				(gr_poly
					(pts
						(arc
							(start -0.1778 -0.2794)
							(mid -0.249642 -0.249642)
							(end -0.2794 -0.1778)
						)
						(arc
							(start -0.2794 0.1778)
							(mid -0.249642 0.249642)
							(end -0.1778 0.2794)
						)
						(arc
							(start 0.1778 0.2794)
							(mid 0.249642 0.249642)
							(end 0.2794 0.1778)
						)
						(arc
							(start 0.2794 -0.1778)
							(mid 0.249642 -0.249642)
							(end 0.1778 -0.2794)
						)
					)
					(width 0)
					(fill yes)
				)
			)
		)
	)
	(footprint ""
		(layer "F.Cu")
		(at 25.5016 -140.5382 90)
		(property "Reference" "PC85"
			(at 0 0 90)
			(layer "F.SilkS")
			(hide yes)
			(effects
				(font
					(size 1.27 1.27)
				)
			)
		)
		(property "Value" "SCD01U25V2KX-3GP"
			(at 1.1811 -2.7051 90)
			(unlocked yes)
			(layer "F.Fab")
			(hide yes)
			(effects
				(font
					(size 1.016 1.016)
					(thickness 0.1524)
				)
			)
		)
		(property "Device Type" "C402H22"
			(at 1.1811 -4.2291 90)
			(unlocked yes)
			(layer "F.Fab")
			(hide yes)
			(effects
				(font
					(size 1.016 1.016)
					(thickness 0.1524)
				)
			)
		)
		(duplicate_pad_numbers_are_jumpers no)
		(fp_rect
			(start -0.4318 0.9525)
			(end 0.4318 -0.9525)
			(stroke
				(width 0)
				(type default)
			)
			(fill no)
			(layer "F.CrtYd")
		)
		(fp_rect
			(start -0.4318 0.9525)
			(end 0.4318 -0.9525)
			(stroke
				(width 0)
				(type default)
			)
			(fill no)
			(layer "F.Fab")
		)
		(pad "1" smd custom
			(at 0 -0.4445 90)
			(size 0.1524 0.1524)
			(layers "F.Cu" "F.Mask" "F.Paste")
			(net "P12VU_2490_RC")
			(options
				(clearance outline)
				(anchor circle)
			)
			(primitives
				(gr_poly
					(pts
						(arc
							(start 0.3048 -0.2032)
							(mid 0.275042 -0.275042)
							(end 0.2032 -0.3048)
						)
						(arc
							(start -0.2032 -0.3048)
							(mid -0.275042 -0.275042)
							(end -0.3048 -0.2032)
						)
						(arc
							(start -0.3048 0.2032)
							(mid -0.275042 0.275042)
							(end -0.2032 0.3048)
						)
						(arc
							(start 0.2032 0.3048)
							(mid 0.275042 0.275042)
							(end 0.3048 0.2032)
						)
					)
					(width 0)
					(fill yes)
				)
			)
		)
		(pad "2" smd custom
			(at 0 0.4445 90)
			(size 0.1524 0.1524)
			(layers "F.Cu" "F.Mask" "F.Paste")
			(net "GND")
			(options
				(clearance outline)
				(anchor circle)
			)
			(primitives
				(gr_poly
					(pts
						(arc
							(start 0.3048 -0.2032)
							(mid 0.275042 -0.275042)
							(end 0.2032 -0.3048)
						)
						(arc
							(start -0.2032 -0.3048)
							(mid -0.275042 -0.275042)
							(end -0.3048 -0.2032)
						)
						(arc
							(start -0.3048 0.2032)
							(mid -0.275042 0.275042)
							(end -0.2032 0.3048)
						)
						(arc
							(start 0.2032 0.3048)
							(mid 0.275042 0.275042)
							(end 0.3048 0.2032)
						)
					)
					(width 0)
					(fill yes)
				)
			)
		)
	)
)
